# S9S_MB_2U (Grand Teton) — schematic netlist excerpt (pin names and nets, part order shuffled) for the footprints in the layout excerpt that follows; sources: Cadence DE-HDL packaged netlist, KiCad conversion of 03242023_DA0F0TMBIJ0_F0T_Motherboard_J_brd_V01_OCP.brd

PR4009  Q_RES  71.5K 1% EMPTY  pkg 0402LF  page 242 : A = P12V_SCM_R ; B = P12V_SCM_OV_FB
R3948  Q_RES  10K 1% CHIP  pkg 0402LF  page 193 : A = P3V3_AUX ; B = HP_LVC3_E1S_0_HSC_PWRGD

(kicad_pcb
	(version 20260206)
	(generator "pcbnew")
	(generator_version "10.0")
	(general
		(thickness 1.6)
		(legacy_teardrops no)
	)
	(paper "A4")
	(title_block
		(title "03242023_DA0F0TMBIJ0_F0T_Motherboard_J_brd_V01_OCP.brd")
		(comment 1 "Grand Teton / footprints 3414-3415 of 6105")
	)
	(layers
		(0 "F.Cu" signal "TOP")
		(4 "In1.Cu" signal "GND")
		(6 "In2.Cu" signal "IN1")
		(8 "In3.Cu" signal "GND1")
		(10 "In4.Cu" signal "IN2")
		(12 "In5.Cu" signal "GND2")
		(14 "In6.Cu" signal "IN3")
		(16 "In7.Cu" signal "GND3")
		(18 "In8.Cu" signal "VCC")
		(20 "In9.Cu" signal "VCC1")
		(22 "In10.Cu" signal "GND4")
		(24 "In11.Cu" signal "IN4")
		(26 "In12.Cu" signal "GND5")
		(28 "In13.Cu" signal "IN5")
		(30 "In14.Cu" signal "GND6")
		(32 "In15.Cu" signal "IN6")
		(34 "In16.Cu" signal "GND7")
		(2 "B.Cu" signal "BOTTOM")
		(9 "F.Adhes" user "F.Adhesive")
		(11 "B.Adhes" user "B.Adhesive")
		(13 "F.Paste" user "Package Geometry/Pastemask Top")
		(15 "B.Paste" user "Package Geometry/Pastemask Bottom")
		(5 "F.SilkS" user "Ref Des/Silkscreen Top")
		(7 "B.SilkS" user "Ref Des/Silkscreen Bottom")
		(1 "F.Mask" user "Board Geometry/Soldermask Top")
		(3 "B.Mask" user "Board Geometry/Soldermask Bottom")
		(17 "Dwgs.User" user "User.Drawings")
		(19 "Cmts.User" user "User.Comments")
		(21 "Eco1.User" user "User.Eco1")
		(23 "Eco2.User" user "User.Eco2")
		(25 "Edge.Cuts" user "Board Geometry/Outline")
		(27 "Margin" user)
		(31 "F.CrtYd" user "Package Geometry/Place Bound Top")
		(29 "B.CrtYd" user "Package Geometry/Place Bound Bottom")
		(35 "F.Fab" user "Ref Des/Assembly Top")
		(33 "B.Fab" user "Ref Des/Assembly Bottom")
	)
	(footprint ""
		(layer "F.Cu")
		(at 254.35433 -54.844442 -90)
		(property "Reference" "R3948"
			(at 0 0 270)
			(layer "F.SilkS")
			(hide yes)
			(effects
				(font
					(size 1.27 1.27)
				)
			)
		)
		(property "Value" ""
			(at 0 0 270)
			(layer "F.Fab")
			(effects
				(font
					(size 1.27 1.27)
				)
			)
		)
		(duplicate_pad_numbers_are_jumpers no)
		(fp_line
			(start -0.7874 0.4064)
			(end -0.7874 -0.4064)
			(stroke
				(width 0.1524)
				(type default)
			)
			(layer "F.SilkS")
		)
		(fp_line
			(start 0.7874 0.4064)
			(end -0.7874 0.4064)
			(stroke
				(width 0.1524)
				(type default)
			)
			(layer "F.SilkS")
		)
		(fp_line
			(start -0.7874 -0.4064)
			(end 0.7874 -0.4064)
			(stroke
				(width 0.1524)
				(type default)
			)
			(layer "F.SilkS")
		)
		(fp_line
			(start 0.7874 -0.4064)
			(end 0.7874 0.4064)
			(stroke
				(width 0.1524)
				(type default)
			)
			(layer "F.SilkS")
		)
		(fp_line
			(start -0.67945 0.3048)
			(end -0.67945 -0.305054)
			(stroke
				(width 0.1)
				(type default)
			)
			(layer "F.Fab")
		)
		(fp_line
			(start -0.12065 0.3048)
			(end -0.67945 0.3048)
			(stroke
				(width 0.1)
				(type default)
			)
			(layer "F.Fab")
		)
		(fp_line
			(start 0.120396 0.3048)
			(end 0.120396 0.2794)
			(stroke
				(width 0.1)
				(type default)
			)
			(layer "F.Fab")
		)
		(fp_line
			(start 0.67945 0.3048)
			(end 0.120396 0.3048)
			(stroke
				(width 0.1)
				(type default)
			)
			(layer "F.Fab")
		)
		(fp_line
			(start -0.12065 0.2794)
			(end -0.12065 0.3048)
			(stroke
				(width 0.1)
				(type default)
			)
			(layer "F.Fab")
		)
		(fp_line
			(start 0.120396 0.2794)
			(end -0.12065 0.2794)
			(stroke
				(width 0.1)
				(type default)
			)
			(layer "F.Fab")
		)
		(fp_line
			(start -0.12065 -0.2794)
			(end 0.12065 -0.2794)
			(stroke
				(width 0.1)
				(type default)
			)
			(layer "F.Fab")
		)
		(fp_line
			(start 0.12065 -0.2794)
			(end 0.12065 -0.3048)
			(stroke
				(width 0.1)
				(type default)
			)
			(layer "F.Fab")
		)
		(fp_line
			(start 0.12065 -0.3048)
			(end 0.67945 -0.3048)
			(stroke
				(width 0.1)
				(type default)
			)
			(layer "F.Fab")
		)
		(fp_line
			(start 0.67945 -0.3048)
			(end 0.67945 0.3048)
			(stroke
				(width 0.1)
				(type default)
			)
			(layer "F.Fab")
		)
		(fp_line
			(start -0.67945 -0.305054)
			(end -0.12065 -0.305054)
			(stroke
				(width 0.1)
				(type default)
			)
			(layer "F.Fab")
		)
		(fp_line
			(start -0.12065 -0.305054)
			(end -0.12065 -0.2794)
			(stroke
				(width 0.1)
				(type default)
			)
			(layer "F.Fab")
		)
		(pad "1" smd circle
			(at -0.40005 0 270)
			(size 0 0)
			(layers "F.Cu" "F.Mask" "F.Paste")
			(net "P3V3_AUX")
		)
		(pad "2" smd circle
			(at 0.40005 0 270)
			(size 0 0)
			(layers "F.Cu" "F.Mask" "F.Paste")
			(net "HP_LVC3_E1S_0_HSC_PWRGD")
		)
	)
	(footprint ""
		(layer "F.Cu")
		(at 171.867322 -28.03779 90)
		(property "Reference" "PR4009"
			(at 0 0 90)
			(layer "F.SilkS")
			(hide yes)
			(effects
				(font
					(size 1.27 1.27)
				)
			)
		)
		(property "Value" ""
			(at 0 0 90)
			(layer "F.Fab")
			(effects
				(font
					(size 1.27 1.27)
				)
			)
		)
		(duplicate_pad_numbers_are_jumpers no)
		(fp_line
			(start 0.7874 -0.4064)
			(end 0.7874 0.4064)
			(stroke
				(width 0.1524)
				(type default)
			)
			(layer "F.SilkS")
		)
		(fp_line
			(start -0.7874 -0.4064)
			(end 0.7874 -0.4064)
			(stroke
				(width 0.1524)
				(type default)
			)
			(layer "F.SilkS")
		)
		(fp_line
			(start 0.7874 0.4064)
			(end -0.7874 0.4064)
			(stroke
				(width 0.1524)
				(type default)
			)
			(layer "F.SilkS")
		)
		(fp_line
			(start -0.7874 0.4064)
			(end -0.7874 -0.4064)
			(stroke
				(width 0.1524)
				(type default)
			)
			(layer "F.SilkS")
		)
		(fp_line
			(start -0.12065 -0.305054)
			(end -0.12065 -0.2794)
			(stroke
				(width 0.1)
				(type default)
			)
			(layer "F.Fab")
		)
		(fp_line
			(start -0.67945 -0.305054)
			(end -0.12065 -0.305054)
			(stroke
				(width 0.1)
				(type default)
			)
			(layer "F.Fab")
		)
		(fp_line
			(start 0.67945 -0.3048)
			(end 0.67945 0.3048)
			(stroke
				(width 0.1)
				(type default)
			)
			(layer "F.Fab")
		)
		(fp_line
			(start 0.12065 -0.3048)
			(end 0.67945 -0.3048)
			(stroke
				(width 0.1)
				(type default)
			)
			(layer "F.Fab")
		)
		(fp_line
			(start 0.12065 -0.2794)
			(end 0.12065 -0.3048)
			(stroke
				(width 0.1)
				(type default)
			)
			(layer "F.Fab")
		)
		(fp_line
			(start -0.12065 -0.2794)
			(end 0.12065 -0.2794)
			(stroke
				(width 0.1)
				(type default)
			)
			(layer "F.Fab")
		)
		(fp_line
			(start 0.120396 0.2794)
			(end -0.12065 0.2794)
			(stroke
				(width 0.1)
				(type default)
			)
			(layer "F.Fab")
		)
		(fp_line
			(start -0.12065 0.2794)
			(end -0.12065 0.3048)
			(stroke
				(width 0.1)
				(type default)
			)
			(layer "F.Fab")
		)
		(fp_line
			(start 0.67945 0.3048)
			(end 0.120396 0.3048)
			(stroke
				(width 0.1)
				(type default)
			)
			(layer "F.Fab")
		)
		(fp_line
			(start 0.120396 0.3048)
			(end 0.120396 0.2794)
			(stroke
				(width 0.1)
				(type default)
			)
			(layer "F.Fab")
		)
		(fp_line
			(start -0.12065 0.3048)
			(end -0.67945 0.3048)
			(stroke
				(width 0.1)
				(type default)
			)
			(layer "F.Fab")
		)
		(fp_line
			(start -0.67945 0.3048)
			(end -0.67945 -0.305054)
			(stroke
				(width 0.1)
				(type default)
			)
			(layer "F.Fab")
		)
		(pad "1" smd circle
			(at -0.40005 0 90)
			(size 0 0)
			(layers "F.Cu" "F.Mask" "F.Paste")
			(net "P12V_SCM_R")
		)
		(pad "2" smd circle
			(at 0.40005 0 90)
			(size 0 0)
			(layers "F.Cu" "F.Mask" "F.Paste")
			(net "P12V_SCM_OV_FB")
		)
	)
)
